# S9S_MB_2U (Grand Teton) — schematic netlist excerpt (pin names and nets, part order shuffled) for the footprints in the layout excerpt that follows; sources: Cadence DE-HDL packaged netlist, KiCad conversion of 03242023_DA0F0TMBIJ0_F0T_Motherboard_J_brd_V01_OCP.brd

J20  SCONN288_ADR50017P087CC  SCONN288_ADR50017-P087CC IO  pkg DDR288S_1-1VXB  page 101
  VIN_BULK0  = P12V_S3_AUX_CPU1_NVDIMM
  RFU0  = TP_CHB_CPU1_DIMM2_FRU_0
  VIN_MGMT  = P3V3_AUX
  HSCL  = I3C_SPD_DDRABCD_CPU1_LVC1_SCL_3
  HSDA  = I3C_SPD_DDRABCD_CPU1_LVC1_SDA
  VSS0  = GND
  DQ0_A  = M_B_CPU1_SA_DQ<0>
  VSS1  = GND
  DQ1_A  = M_B_CPU1_SA_DQ<1>
  VSS2  = GND
  DQS0_A_T  = M_B_CPU1_SA_DQS_DP<0>
  DQS0_A_C  = M_B_CPU1_SA_DQS_DN<0>
  VSS3  = GND
  DQ4_A  = M_B_CPU1_SA_DQ<4>
  VSS4  = GND
  DQ5_A  = M_B_CPU1_SA_DQ<5>
  VSS5  = GND
  DQ8_A  = M_B_CPU1_SA_DQ<8>
  VSS6  = GND
  DQ9_A  = M_B_CPU1_SA_DQ<9>
  VSS7  = GND
  DQS1_A_T  = M_B_CPU1_SA_DQS_DP<1>
  DQS1_A_C  = M_B_CPU1_SA_DQS_DN<1>
  VSS8  = GND
  DQ12_A  = M_B_CPU1_SA_DQ<12>
  VSS9  = GND
  DQ13_A  = M_B_CPU1_SA_DQ<13>
  VSS10  = GND
  DQ16_A  = M_B_CPU1_SA_DQ<16>
  VSS11  = GND
  DQ17_A  = M_B_CPU1_SA_DQ<17>
  VSS12  = GND
  DQS2_A_T  = M_B_CPU1_SA_DQS_DP<2>
  DQS2_A_C  = M_B_CPU1_SA_DQS_DN<2>
  VSS13  = GND
  DQ20_A  = M_B_CPU1_SA_DQ<20>
  VSS14  = GND
  DQ21_A  = M_B_CPU1_SA_DQ<21>
  VSS15  = GND
  DQ24_A  = M_B_CPU1_SA_DQ<24>
  VSS16  = GND
  DQ25_A  = M_B_CPU1_SA_DQ<25>
  VSS17  = GND
  DQS3_A_T  = M_B_CPU1_SA_DQS_DP<3>
  DQS3_A_C  = M_B_CPU1_SA_DQS_DN<3>
  VSS18  = GND
  DQ28_A  = M_B_CPU1_SA_DQ<28>
  VSS19  = GND
  DQ29_A  = M_B_CPU1_SA_DQ<29>
  VSS20  = GND
  CB0_A  = M_B_CPU1_SA_CB<0>
  VSS21  = GND
  CB1_A  = M_B_CPU1_SA_CB<1>
  VSS22  = GND
  DQS4_A_T  = M_B_CPU1_SA_DQS_DP<4>
  DQS4_A_C  = M_B_CPU1_SA_DQS_DN<4>
  VSS23  = GND
  CB4_A  = M_B_CPU1_SA_CB<4>
  VSS24  = GND
  CB5_A  = M_B_CPU1_SA_CB<5>
  VSS25  = GND
  ALERT_N  = M_B_CPU1_ALERT_N
  VSS26  = GND
  CS0_A_N  = M_B_CPU1_SA_CS_N<2>
  VSS27  = GND
  CA0_A  = M_B_CPU1_SA_CA<0>
  VSS28  = GND
  CA2_A  = M_B_CPU1_SA_CA<2>
  VSS29  = GND
  CA4_A  = M_B_CPU1_SA_CA<4>
  VSS30  = GND
  CA6_A  = M_B_CPU1_SA_CA<6>
  VSS31  = GND
  PAR_A  = M_B_CPU1_SA_PAR
  VSS32  = GND
  CA0_B  = M_B_CPU1_SB_CA<0>
  VSS33  = GND
  CA2_B  = M_B_CPU1_SB_CA<2>
  VSS34  = GND
  CA4_B  = M_B_CPU1_SB_CA<4>
  VSS35  = GND
  CA6_B  = M_B_CPU1_SB_CA<6>
  VSS36  = GND
  CS0_B_N  = M_B_CPU1_SB_CS_N<2>
  VSS37  = GND
  \lbd||rsp_a_n\  = M_B_CPU1_SA_RSP<1>
  \lbs||rsp_b_n\  = M_B_CPU1_SB_RSP<1>
  VSS38  = GND
  CB4_B  = M_B_CPU1_SB_CB<4>
  VSS39  = GND
  CB5_B  = M_B_CPU1_SB_CB<5>
  VSS40  = GND
  \dqs9_b_t||tdqs9_b_t||dbi4_b_n\  = M_B_CPU1_SB_DQS_DP<9>
  \dqs9_b_c||tdqs9_b_c\  = M_B_CPU1_SB_DQS_DN<9>
  VSS41  = GND
  CB0_B  = M_B_CPU1_SB_CB<0>
  VSS42  = GND
  CB1_B  = M_B_CPU1_SB_CB<1>
  VSS43  = GND
  DQ0_B  = M_B_CPU1_SB_DQ<0>
  VSS44  = GND
  DQ1_B  = M_B_CPU1_SB_DQ<1>
  VSS45  = GND
  DQS0_B_T  = M_B_CPU1_SB_DQS_DP<0>
  DQS0_B_C  = M_B_CPU1_SB_DQS_DN<0>
  VSS46  = GND
  DQ4_B  = M_B_CPU1_SB_DQ<4>
  VSS47  = GND
  DQ5_B  = M_B_CPU1_SB_DQ<5>
  VSS48  = GND
  DQ8_B  = M_B_CPU1_SB_DQ<8>
  VSS49  = GND
  DQ9_B  = M_B_CPU1_SB_DQ<9>
  VSS50  = GND
  DQS1_B_T  = M_B_CPU1_SB_DQS_DP<1>
  DQS1_B_C  = M_B_CPU1_SB_DQS_DN<1>
  VSS51  = GND
  DQ12_B  = M_B_CPU1_SB_DQ<12>
  VSS52  = GND
  DQ13_B  = M_B_CPU1_SB_DQ<13>
  VSS53  = GND
  DQ16_B  = M_B_CPU1_SB_DQ<16>
  VSS54  = GND
  DQ17_B  = M_B_CPU1_SB_DQ<17>
  VSS55  = GND
  DQS2_B_T  = M_B_CPU1_SB_DQS_DP<2>
  DQS2_B_C  = M_B_CPU1_SB_DQS_DN<2>
  VSS56  = GND
  DQ20_B  = M_B_CPU1_SB_DQ<20>
  VSS57  = GND
  DQ21_B  = M_B_CPU1_SB_DQ<21>
  VSS58  = GND
  DQ24_B  = M_B_CPU1_SB_DQ<24>
  VSS59  = GND
  DQ25_B  = M_B_CPU1_SB_DQ<25>
  VSS60  = GND
  DQS3_B_T  = M_B_CPU1_SB_DQS_DP<3>
  DQS3_B_C  = M_B_CPU1_SB_DQS_DN<3>
  VSS61  = GND
  DQ28_B  = M_B_CPU1_SB_DQ<28>
  VSS62  = GND
  DQ29_B  = M_B_CPU1_SB_DQ<29>
  VSS63  = GND
  RFU1  = TP_CHB_CPU1_DIMM2_FRU_1
  VIN_BULK1  = P12V_S3_AUX_CPU1_NVDIMM
  VIN_BULK2  = P12V_S3_AUX_CPU1_NVDIMM
  \pwr_good||fail_n\  = PWRGD_CHB_CPU1_DIMM2
  HSA  = PD_CHB_CPU1_DIMM2_SAA
  RFU2  = TP_CHB_CPU1_DIMM2_FRU_2
  RFU3  = TP_CHB_CPU1_DIMM2_FRU_3
  VSS64  = GND
  DQ2_A  = M_B_CPU1_SA_DQ<2>
  VSS65  = GND
  DQ3_A  = M_B_CPU1_SA_DQ<3>
  VSS66  = GND
  \dqs5_a_c||tdqs5_a_c||dqs5_a_t||tdqs5_a_t\  = M_B_CPU1_SA_DQS_DN<5>
  \dqs5_a_t||tdqs5_a_t\  = M_B_CPU1_SA_DQS_DP<5>
  VSS67  = GND
  DQ6_A  = M_B_CPU1_SA_DQ<6>
  VSS68  = GND
  DQ7_A  = M_B_CPU1_SA_DQ<7>
  VSS69  = GND
  DQ10_A  = M_B_CPU1_SA_DQ<10>
  VSS70  = GND
  DQ11_A  = M_B_CPU1_SA_DQ<11>
  VSS71  = GND
  \dqs6_a_c||tdqs6_a_c||dqs6_a_t||tdqs6_a_t\  = M_B_CPU1_SA_DQS_DN<6>
  \dqs6_a_t||tdqs6_a_t\  = M_B_CPU1_SA_DQS_DP<6>
  VSS72  = GND
  DQ14_A  = M_B_CPU1_SA_DQ<14>
  VSS73  = GND
  DQ15_A  = M_B_CPU1_SA_DQ<15>
  VSS74  = GND
  DQ18_A  = M_B_CPU1_SA_DQ<18>
  VSS75  = GND
  DQ19_A  = M_B_CPU1_SA_DQ<19>
  VSS76  = GND
  \dqs7_a_c||tdqs7_a_c\  = M_B_CPU1_SA_DQS_DN<7>
  \dqs7_a_t||tdqs7_a_t\  = M_B_CPU1_SA_DQS_DP<7>
  VSS77  = GND
  DQ22_A  = M_B_CPU1_SA_DQ<22>
  VSS78  = GND
  DQ23_A  = M_B_CPU1_SA_DQ<23>
  VSS79  = GND
  DQ26_A  = M_B_CPU1_SA_DQ<26>
  VSS80  = GND
  DQ27_A  = M_B_CPU1_SA_DQ<27>
  VSS81  = GND
  \dqs8_a_c||tdqs8_a_c\  = M_B_CPU1_SA_DQS_DN<8>
  \dqs8_a_t||tdqs8_a_t\  = M_B_CPU1_SA_DQS_DP<8>
  VSS82  = GND
  DQ30_A  = M_B_CPU1_SA_DQ<30>
  VSS83  = GND
  DQ31_A  = M_B_CPU1_SA_DQ<31>
  VSS84  = GND
  CB2_A  = M_B_CPU1_SA_CB<2>
  VSS85  = GND
  CB3_A  = M_B_CPU1_SA_CB<3>
  VSS86  = GND
  \dqs9_a_c||tdqs9_a_c\  = M_B_CPU1_SA_DQS_DN<9>
  \dqs9_a_t||tdqs9_a_t\  = M_B_CPU1_SA_DQS_DP<9>
  VSS87  = GND
  CB6_A  = M_B_CPU1_SA_CB<6>
  VSS88  = GND
  CB7_A  = M_B_CPU1_SA_CB<7>
  VSS89  = GND
  RESET_N  = RST_M_AB_CPU1_FPGA_N
  VSS90  = GND
  CS1_A_N  = M_B_CPU1_SA_CS_N<3>
  VSS91  = GND
  CA1_A  = M_B_CPU1_SA_CA<1>
  VSS92  = GND
  CA3_A  = M_B_CPU1_SA_CA<3>
  VSS93  = GND
  CA5_A  = M_B_CPU1_SA_CA<5>
  VSS94  = GND
  CK_T  = M_B_CPU1_CLK_DP<1>
  CK_C  = M_B_CPU1_CLK_DN<1>
  VSS95  = GND
  RFU4  = TP_CHB_CPU1_DIMM2_FRU_4
  CA1_B  = M_B_CPU1_SB_CA<1>
  VSS96  = GND
  CA3_B  = M_B_CPU1_SB_CA<3>
  VSS97  = GND
  CA5_B  = M_B_CPU1_SB_CA<5>
  VSS98  = GND
  PAR_B  = M_B_CPU1_SB_PAR
  VSS99  = GND
  CS1_B_N  = M_B_CPU1_SB_CS_N<3>
  VSS100  = GND
  RFU5  = TP_CHB_CPU1_DIMM2_FRU_5
  RFU6  = TP_CHB_CPU1_DIMM2_FRU_6
  VSS101  = GND
  CB6_B  = M_B_CPU1_SB_CB<6>
  VSS102  = GND
  CB7_B  = M_B_CPU1_SB_CB<7>
  VSS103  = GND
  DQS4_B_C  = M_B_CPU1_SB_DQS_DN<4>
  DQS4_B_T  = M_B_CPU1_SB_DQS_DP<4>
  VSS104  = GND
  CB2_B  = M_B_CPU1_SB_CB<2>
  VSS105  = GND
  CB3_B  = M_B_CPU1_SB_CB<3>
  VSS106  = GND
  DQ2_B  = M_B_CPU1_SB_DQ<2>
  VSS107  = GND
  DQ3_B  = M_B_CPU1_SB_DQ<3>
  VSS108  = GND
  \dqs5_b_c||tdqs5_b_c\  = M_B_CPU1_SB_DQS_DN<5>
  \dqs5_b_t||tdqs5_b_t\  = M_B_CPU1_SB_DQS_DP<5>
  VSS109  = GND
  DQ6_B  = M_B_CPU1_SB_DQ<6>
  VSS110  = GND
  DQ7_B  = M_B_CPU1_SB_DQ<7>
  VSS111  = GND
  DQ10_B  = M_B_CPU1_SB_DQ<10>
  VSS112  = GND
  DQ11_B  = M_B_CPU1_SB_DQ<11>
  VSS113  = GND
  \dqs6_b_c||tdqs6_b_c\  = M_B_CPU1_SB_DQS_DN<6>
  \dqs6_b_t||tdqs6_b_t\  = M_B_CPU1_SB_DQS_DP<6>
  VSS114  = GND
  DQ14_B  = M_B_CPU1_SB_DQ<14>
  VSS115  = GND
  DQ15_B  = M_B_CPU1_SB_DQ<15>
  VSS116  = GND
  DQ18_B  = M_B_CPU1_SB_DQ<18>
  VSS117  = GND
  DQ19_B  = M_B_CPU1_SB_DQ<19>
  VSS118  = GND
  \dqs7_b_c||tdqs7_b_c\  = M_B_CPU1_SB_DQS_DN<7>
  \dqs7_b_t||tdqs7_b_t\  = M_B_CPU1_SB_DQS_DP<7>
  VSS119  = GND
  DQ22_B  = M_B_CPU1_SB_DQ<22>
  VSS120  = GND
  DQ23_B  = M_B_CPU1_SB_DQ<23>
  VSS121  = GND
  DQ26_B  = M_B_CPU1_SB_DQ<26>
  VSS122  = GND
  DQ27_B  = M_B_CPU1_SB_DQ<27>
  VSS123  = GND
  \dqs8_b_c||tdqs8_b_c\  = M_B_CPU1_SB_DQS_DN<8>
  \dqs8_b_t||tdqs8_b_t\  = M_B_CPU1_SB_DQS_DP<8>
  VSS124  = GND
  DQ30_B  = M_B_CPU1_SB_DQ<30>
  VSS125  = GND
  DQ31_B  = M_B_CPU1_SB_DQ<31>
  VSS126  = GND
  G1  = GND
  G2  = GND
  G3  = GND

(kicad_pcb
	(version 20260206)
	(generator "pcbnew")
	(generator_version "10.0")
	(general
		(thickness 1.6)
		(legacy_teardrops no)
	)
	(paper "A4")
	(title_block
		(title "03242023_DA0F0TMBIJ0_F0T_Motherboard_J_brd_V01_OCP.brd")
		(comment 1 "Grand Teton / footprint 1508 of 6105 (J20), pads 229-274 of 291")
	)
	(layers
		(0 "F.Cu" signal "TOP")
		(4 "In1.Cu" signal "GND")
		(6 "In2.Cu" signal "IN1")
		(8 "In3.Cu" signal "GND1")
		(10 "In4.Cu" signal "IN2")
		(12 "In5.Cu" signal "GND2")
		(14 "In6.Cu" signal "IN3")
		(16 "In7.Cu" signal "GND3")
		(18 "In8.Cu" signal "VCC")
		(20 "In9.Cu" signal "VCC1")
		(22 "In10.Cu" signal "GND4")
		(24 "In11.Cu" signal "IN4")
		(26 "In12.Cu" signal "GND5")
		(28 "In13.Cu" signal "IN5")
		(30 "In14.Cu" signal "GND6")
		(32 "In15.Cu" signal "IN6")
		(34 "In16.Cu" signal "GND7")
		(2 "B.Cu" signal "BOTTOM")
		(9 "F.Adhes" user "F.Adhesive")
		(11 "B.Adhes" user "B.Adhesive")
		(13 "F.Paste" user "Package Geometry/Pastemask Top")
		(15 "B.Paste" user "Package Geometry/Pastemask Bottom")
		(5 "F.SilkS" user "Ref Des/Silkscreen Top")
		(7 "B.SilkS" user "Ref Des/Silkscreen Bottom")
		(1 "F.Mask" user "Board Geometry/Soldermask Top")
		(3 "B.Mask" user "Board Geometry/Soldermask Bottom")
		(17 "Dwgs.User" user "User.Drawings")
		(19 "Cmts.User" user "User.Comments")
		(21 "Eco1.User" user "User.Eco1")
		(23 "Eco2.User" user "User.Eco2")
		(25 "Edge.Cuts" user "Board Geometry/Outline")
		(27 "Margin" user)
		(31 "F.CrtYd" user "Package Geometry/Place Bound Top")
		(29 "B.CrtYd" user "Package Geometry/Place Bound Bottom")
		(35 "F.Fab" user "Ref Des/Assembly Top")
		(33 "B.Fab" user "Ref Des/Assembly Bottom")
	)
	(footprint ""
		(layer "F.Cu")
		(at 47.90948 -258.091686)
		(property "Reference" "J20"
			(at -2.74066 -81.678272 0)
			(unlocked yes)
			(layer "F.SilkS")
			(effects
				(font
					(size 0.7874 0.5842)
					(thickness 0.1524)
				)
				(justify left)
			)
		)
		(property "Value" ""
			(at 0 0 0)
			(layer "F.Fab")
			(effects
				(font
					(size 1.27 1.27)
				)
			)
		)
		(duplicate_pad_numbers_are_jumpers no)
		(pad "229" smd rect
			(at 2.050034 13.17498 270)
			(size 0.519938 1.4986)
			(layers "F.Cu" "F.Mask" "F.Paste")
			(net "M_B_CPU1_SB_CS_N<3>")
		)
		(pad "230" smd rect
			(at 2.050034 14.025118 270)
			(size 0.519938 1.4986)
			(layers "F.Cu" "F.Mask" "F.Paste")
			(net "GND")
		)
		(pad "231" smd rect
			(at 2.050034 14.875002 270)
			(size 0.519938 1.4986)
			(layers "F.Cu" "F.Mask" "F.Paste")
			(net "TP_CHB_CPU1_DIMM2_FRU_5")
		)
		(pad "232" smd rect
			(at 2.050034 15.724886 270)
			(size 0.519938 1.4986)
			(layers "F.Cu" "F.Mask" "F.Paste")
			(net "TP_CHB_CPU1_DIMM2_FRU_6")
		)
		(pad "233" smd rect
			(at 2.050034 16.575024 270)
			(size 0.519938 1.4986)
			(layers "F.Cu" "F.Mask" "F.Paste")
			(net "GND")
		)
		(pad "234" smd rect
			(at 2.050034 17.424908 270)
			(size 0.519938 1.4986)
			(layers "F.Cu" "F.Mask" "F.Paste")
			(net "M_B_CPU1_SB_CB<6>")
		)
		(pad "235" smd rect
			(at 2.050034 18.275046 270)
			(size 0.519938 1.4986)
			(layers "F.Cu" "F.Mask" "F.Paste")
			(net "GND")
		)
		(pad "236" smd rect
			(at 2.050034 19.12493 270)
			(size 0.519938 1.4986)
			(layers "F.Cu" "F.Mask" "F.Paste")
			(net "M_B_CPU1_SB_CB<7>")
		)
		(pad "237" smd rect
			(at 2.050034 19.975068 270)
			(size 0.519938 1.4986)
			(layers "F.Cu" "F.Mask" "F.Paste")
			(net "GND")
		)
		(pad "238" smd rect
			(at 2.050034 20.824952 270)
			(size 0.519938 1.4986)
			(layers "F.Cu" "F.Mask" "F.Paste")
			(net "M_B_CPU1_SB_DQS_DN<4>")
		)
		(pad "239" smd rect
			(at 2.050034 21.67509 270)
			(size 0.519938 1.4986)
			(layers "F.Cu" "F.Mask" "F.Paste")
			(net "M_B_CPU1_SB_DQS_DP<4>")
		)
		(pad "240" smd rect
			(at 2.050034 22.524974 270)
			(size 0.519938 1.4986)
			(layers "F.Cu" "F.Mask" "F.Paste")
			(net "GND")
		)
		(pad "241" smd rect
			(at 2.050034 23.375112 270)
			(size 0.519938 1.4986)
			(layers "F.Cu" "F.Mask" "F.Paste")
			(net "M_B_CPU1_SB_CB<2>")
		)
		(pad "242" smd rect
			(at 2.050034 24.224996 270)
			(size 0.519938 1.4986)
			(layers "F.Cu" "F.Mask" "F.Paste")
			(net "GND")
		)
		(pad "243" smd rect
			(at 2.050034 25.07488 270)
			(size 0.519938 1.4986)
			(layers "F.Cu" "F.Mask" "F.Paste")
			(net "M_B_CPU1_SB_CB<3>")
		)
		(pad "244" smd rect
			(at 2.050034 25.925018 270)
			(size 0.519938 1.4986)
			(layers "F.Cu" "F.Mask" "F.Paste")
			(net "GND")
		)
		(pad "245" smd rect
			(at 2.050034 26.774902 270)
			(size 0.519938 1.4986)
			(layers "F.Cu" "F.Mask" "F.Paste")
			(net "M_B_CPU1_SB_DQ<2>")
		)
		(pad "246" smd rect
			(at 2.050034 27.62504 270)
			(size 0.519938 1.4986)
			(layers "F.Cu" "F.Mask" "F.Paste")
			(net "GND")
		)
		(pad "247" smd rect
			(at 2.050034 28.474924 270)
			(size 0.519938 1.4986)
			(layers "F.Cu" "F.Mask" "F.Paste")
			(net "M_B_CPU1_SB_DQ<3>")
		)
		(pad "248" smd rect
			(at 2.050034 29.325062 270)
			(size 0.519938 1.4986)
			(layers "F.Cu" "F.Mask" "F.Paste")
			(net "GND")
		)
		(pad "249" smd rect
			(at 2.050034 30.174946 270)
			(size 0.519938 1.4986)
			(layers "F.Cu" "F.Mask" "F.Paste")
			(net "M_B_CPU1_SB_DQS_DN<5>")
		)
		(pad "250" smd rect
			(at 2.050034 31.025084 270)
			(size 0.519938 1.4986)
			(layers "F.Cu" "F.Mask" "F.Paste")
			(net "M_B_CPU1_SB_DQS_DP<5>")
		)
		(pad "251" smd rect
			(at 2.050034 31.874968 270)
			(size 0.519938 1.4986)
			(layers "F.Cu" "F.Mask" "F.Paste")
			(net "GND")
		)
		(pad "252" smd rect
			(at 2.050034 32.725106 270)
			(size 0.519938 1.4986)
			(layers "F.Cu" "F.Mask" "F.Paste")
			(net "M_B_CPU1_SB_DQ<6>")
		)
		(pad "253" smd rect
			(at 2.050034 33.57499 270)
			(size 0.519938 1.4986)
			(layers "F.Cu" "F.Mask" "F.Paste")
			(net "GND")
		)
		(pad "254" smd rect
			(at 2.050034 34.425128 270)
			(size 0.519938 1.4986)
			(layers "F.Cu" "F.Mask" "F.Paste")
			(net "M_B_CPU1_SB_DQ<7>")
		)
		(pad "255" smd rect
			(at 2.050034 35.275012 270)
			(size 0.519938 1.4986)
			(layers "F.Cu" "F.Mask" "F.Paste")
			(net "GND")
		)
		(pad "256" smd rect
			(at 2.050034 36.124896 270)
			(size 0.519938 1.4986)
			(layers "F.Cu" "F.Mask" "F.Paste")
			(net "M_B_CPU1_SB_DQ<10>")
		)
		(pad "257" smd rect
			(at 2.050034 36.975034 270)
			(size 0.519938 1.4986)
			(layers "F.Cu" "F.Mask" "F.Paste")
			(net "GND")
		)
		(pad "258" smd rect
			(at 2.050034 37.824918 270)
			(size 0.519938 1.4986)
			(layers "F.Cu" "F.Mask" "F.Paste")
			(net "M_B_CPU1_SB_DQ<11>")
		)
		(pad "259" smd rect
			(at 2.050034 38.675056 270)
			(size 0.519938 1.4986)
			(layers "F.Cu" "F.Mask" "F.Paste")
			(net "GND")
		)
		(pad "260" smd rect
			(at 2.050034 39.52494 270)
			(size 0.519938 1.4986)
			(layers "F.Cu" "F.Mask" "F.Paste")
			(net "M_B_CPU1_SB_DQS_DN<6>")
		)
		(pad "261" smd rect
			(at 2.050034 40.375078 270)
			(size 0.519938 1.4986)
			(layers "F.Cu" "F.Mask" "F.Paste")
			(net "M_B_CPU1_SB_DQS_DP<6>")
		)
		(pad "262" smd rect
			(at 2.050034 41.224962 270)
			(size 0.519938 1.4986)
			(layers "F.Cu" "F.Mask" "F.Paste")
			(net "GND")
		)
		(pad "263" smd rect
			(at 2.050034 42.0751 270)
			(size 0.519938 1.4986)
			(layers "F.Cu" "F.Mask" "F.Paste")
			(net "M_B_CPU1_SB_DQ<14>")
		)
		(pad "264" smd rect
			(at 2.050034 42.924984 270)
			(size 0.519938 1.4986)
			(layers "F.Cu" "F.Mask" "F.Paste")
			(net "GND")
		)
		(pad "265" smd rect
			(at 2.050034 43.775122 270)
			(size 0.519938 1.4986)
			(layers "F.Cu" "F.Mask" "F.Paste")
			(net "M_B_CPU1_SB_DQ<15>")
		)
		(pad "266" smd rect
			(at 2.050034 44.625006 270)
			(size 0.519938 1.4986)
			(layers "F.Cu" "F.Mask" "F.Paste")
			(net "GND")
		)
		(pad "267" smd rect
			(at 2.050034 45.47489 270)
			(size 0.519938 1.4986)
			(layers "F.Cu" "F.Mask" "F.Paste")
			(net "M_B_CPU1_SB_DQ<18>")
		)
		(pad "268" smd rect
			(at 2.050034 46.325028 270)
			(size 0.519938 1.4986)
			(layers "F.Cu" "F.Mask" "F.Paste")
			(net "GND")
		)
		(pad "269" smd rect
			(at 2.050034 47.174912 270)
			(size 0.519938 1.4986)
			(layers "F.Cu" "F.Mask" "F.Paste")
			(net "M_B_CPU1_SB_DQ<19>")
		)
		(pad "270" smd rect
			(at 2.050034 48.02505 270)
			(size 0.519938 1.4986)
			(layers "F.Cu" "F.Mask" "F.Paste")
			(net "GND")
		)
		(pad "271" smd rect
			(at 2.050034 48.874934 270)
			(size 0.519938 1.4986)
			(layers "F.Cu" "F.Mask" "F.Paste")
			(net "M_B_CPU1_SB_DQS_DN<7>")
		)
		(pad "272" smd rect
			(at 2.050034 49.725072 270)
			(size 0.519938 1.4986)
			(layers "F.Cu" "F.Mask" "F.Paste")
			(net "M_B_CPU1_SB_DQS_DP<7>")
		)
		(pad "273" smd rect
			(at 2.050034 50.574956 270)
			(size 0.519938 1.4986)
			(layers "F.Cu" "F.Mask" "F.Paste")
			(net "GND")
		)
		(pad "274" smd rect
			(at 2.050034 51.425094 270)
			(size 0.519938 1.4986)
			(layers "F.Cu" "F.Mask" "F.Paste")
			(net "M_B_CPU1_SB_DQ<22>")
		)
	)
)
